(kicad_pcb
	(version 20260206)
	(generator "pcbnew")
	(generator_version "10.0")
	(general
		(thickness 1.6)
		(legacy_teardrops no)
	)
	(paper "A4")
	(title_block
		(title "peb — Lightning_PEB_BRD.brd")
		(comment 1 "Lightning (Wiwynn / Facebook NVMe JBOF) / footprints 2476-2483 of 2563")
	)
	(layers
		(0 "F.Cu" signal "TOP")
		(4 "In1.Cu" signal "L2GND")
		(6 "In2.Cu" signal "L3")
		(8 "In3.Cu" signal "L4VCC")
		(10 "In4.Cu" signal "L5VCC")
		(12 "In5.Cu" signal "L6")
		(14 "In6.Cu" signal "L7GND")
		(2 "B.Cu" signal "BOTTOM")
		(9 "F.Adhes" user "F.Adhesive")
		(11 "B.Adhes" user "B.Adhesive")
		(13 "F.Paste" user "Package Geometry/Pastemask Top")
		(15 "B.Paste" user "Package Geometry/Pastemask Bottom")
		(5 "F.SilkS" user "Ref Des/Silkscreen Top")
		(7 "B.SilkS" user "Ref Des/Silkscreen Bottom")
		(1 "F.Mask" user "Board Geometry/Soldermask Top")
		(3 "B.Mask" user "Board Geometry/Soldermask Bottom")
		(17 "Dwgs.User" user "User.Drawings")
		(19 "Cmts.User" user "User.Comments")
		(21 "Eco1.User" user "User.Eco1")
		(23 "Eco2.User" user "User.Eco2")
		(25 "Edge.Cuts" user "Board Geometry/Outline")
		(27 "Margin" user)
		(31 "F.CrtYd" user "Package Geometry/Place Bound Top")
		(29 "B.CrtYd" user "Package Geometry/Place Bound Bottom")
		(35 "F.Fab" user "Ref Des/Assembly Top")
		(33 "B.Fab" user "Ref Des/Assembly Bottom")
	)
	(footprint ""
		(layer "B.Cu")
		(at 245.5926 -59.9948 90)
		(property "Reference" "C504"
			(at 0 0 90)
			(layer "B.SilkS")
			(hide yes)
			(effects
				(font
					(size 1.27 1.27)
				)
				(justify mirror)
			)
		)
		(property "Value" "SCD1U16V1KX-1-GP"
			(at 2.8321 -1.7399 90)
			(unlocked yes)
			(layer "B.Fab")
			(hide yes)
			(effects
				(font
					(size 1.016 1.016)
					(thickness 0.1524)
				)
				(justify mirror)
			)
		)
		(property "Device Type" "C0201H13"
			(at 2.8321 -3.2639 90)
			(unlocked yes)
			(layer "B.Fab")
			(hide yes)
			(effects
				(font
					(size 1.016 1.016)
					(thickness 0.1524)
				)
				(justify mirror)
			)
		)
		(duplicate_pad_numbers_are_jumpers no)
		(fp_rect
			(start 0.2794 0.6477)
			(end -0.2794 -0.6477)
			(stroke
				(width 0)
				(type default)
			)
			(fill no)
			(layer "B.CrtYd")
		)
		(fp_rect
			(start 0.2794 0.6477)
			(end -0.2794 -0.6477)
			(stroke
				(width 0)
				(type default)
			)
			(fill no)
			(layer "B.Fab")
		)
		(pad "1" smd custom
			(at 0 -0.2794 270)
			(size 0.0762 0.0762)
			(layers "B.Cu" "B.Mask" "B.Paste")
			(net "DUT_AVD_TX")
			(options
				(clearance outline)
				(anchor circle)
			)
			(primitives
				(gr_poly
					(pts
						(arc
							(start 0.1524 0.127)
							(mid 0.137521 0.162921)
							(end 0.1016 0.1778)
						)
						(arc
							(start -0.1016 0.1778)
							(mid -0.137521 0.162921)
							(end -0.1524 0.127)
						)
						(arc
							(start -0.1524 -0.127)
							(mid -0.137521 -0.162921)
							(end -0.1016 -0.1778)
						)
						(arc
							(start 0.1016 -0.1778)
							(mid 0.137521 -0.162921)
							(end 0.1524 -0.127)
						)
					)
					(width 0)
					(fill yes)
				)
			)
		)
		(pad "2" smd custom
			(at 0 0.2794 270)
			(size 0.0762 0.0762)
			(layers "B.Cu" "B.Mask" "B.Paste")
			(net "GND")
			(options
				(clearance outline)
				(anchor circle)
			)
			(primitives
				(gr_poly
					(pts
						(arc
							(start 0.1524 0.127)
							(mid 0.137521 0.162921)
							(end 0.1016 0.1778)
						)
						(arc
							(start -0.1016 0.1778)
							(mid -0.137521 0.162921)
							(end -0.1524 0.127)
						)
						(arc
							(start -0.1524 -0.127)
							(mid -0.137521 -0.162921)
							(end -0.1016 -0.1778)
						)
						(arc
							(start 0.1016 -0.1778)
							(mid 0.137521 -0.162921)
							(end 0.1524 -0.127)
						)
					)
					(width 0)
					(fill yes)
				)
			)
		)
	)
	(footprint ""
		(layer "B.Cu")
		(at 136.824212 -205.849474)
		(property "Reference" "R3219"
			(at 0 0 0)
			(layer "B.SilkS")
			(hide yes)
			(effects
				(font
					(size 1.27 1.27)
				)
				(justify mirror)
			)
		)
		(property "Value" "0R2J-2-GP"
			(at -0.064008 -3.993896 0)
			(unlocked yes)
			(layer "B.Fab")
			(hide yes)
			(effects
				(font
					(size 1.016 1.016)
					(thickness 0.1524)
				)
				(justify mirror)
			)
		)
		(property "Device Type" "R402H16"
			(at -0.064008 -5.517896 0)
			(unlocked yes)
			(layer "B.Fab")
			(hide yes)
			(effects
				(font
					(size 1.016 1.016)
					(thickness 0.1524)
				)
				(justify mirror)
			)
		)
		(duplicate_pad_numbers_are_jumpers no)
		(fp_line
			(start -0.508 -0.9398)
			(end 0.508 -0.9398)
			(stroke
				(width 0.1524)
				(type default)
			)
			(layer "B.SilkS")
		)
		(fp_line
			(start 0.508 -0.9398)
			(end 0.508 0.9398)
			(stroke
				(width 0.1524)
				(type default)
			)
			(layer "B.SilkS")
		)
		(fp_rect
			(start 0.508 0.9398)
			(end -0.508 -0.9398)
			(stroke
				(width 0)
				(type default)
			)
			(fill no)
			(layer "B.CrtYd")
		)
		(fp_rect
			(start 0.508 0.9398)
			(end -0.508 -0.9398)
			(stroke
				(width 0)
				(type default)
			)
			(fill no)
			(layer "B.Fab")
		)
		(pad "1" smd custom
			(at 0 -0.4445 180)
			(size 0.1397 0.1397)
			(layers "B.Cu" "B.Mask" "B.Paste")
			(net "SSD_PERST#6")
			(options
				(clearance outline)
				(anchor circle)
			)
			(primitives
				(gr_poly
					(pts
						(arc
							(start -0.1778 0.2794)
							(mid -0.249642 0.249642)
							(end -0.2794 0.1778)
						)
						(arc
							(start -0.2794 -0.1778)
							(mid -0.249642 -0.249642)
							(end -0.1778 -0.2794)
						)
						(arc
							(start 0.1778 -0.2794)
							(mid 0.249642 -0.249642)
							(end 0.2794 -0.1778)
						)
						(arc
							(start 0.2794 0.1778)
							(mid 0.249642 0.249642)
							(end 0.1778 0.2794)
						)
					)
					(width 0)
					(fill yes)
				)
			)
		)
		(pad "2" smd custom
			(at 0 0.4445 180)
			(size 0.1397 0.1397)
			(layers "B.Cu" "B.Mask" "B.Paste")
			(net "SSD_PERST#0_B6")
			(options
				(clearance outline)
				(anchor circle)
			)
			(primitives
				(gr_poly
					(pts
						(arc
							(start -0.1778 0.2794)
							(mid -0.249642 0.249642)
							(end -0.2794 0.1778)
						)
						(arc
							(start -0.2794 -0.1778)
							(mid -0.249642 -0.249642)
							(end -0.1778 -0.2794)
						)
						(arc
							(start 0.1778 -0.2794)
							(mid 0.249642 -0.249642)
							(end 0.2794 -0.1778)
						)
						(arc
							(start 0.2794 0.1778)
							(mid 0.249642 0.249642)
							(end 0.1778 0.2794)
						)
					)
					(width 0)
					(fill yes)
				)
			)
		)
	)
	(footprint ""
		(layer "B.Cu")
		(at 40.005 -116.332)
		(property "Reference" "TP324"
			(at 0 0 0)
			(layer "B.SilkS")
			(hide yes)
			(effects
				(font
					(size 1.27 1.27)
				)
				(justify mirror)
			)
		)
		(property "Value" "TPAD28-2-GP"
			(at 0.0127 -1.6637 0)
			(unlocked yes)
			(layer "B.Fab")
			(hide yes)
			(effects
				(font
					(size 1.016 1.016)
					(thickness 0.1524)
				)
				(justify mirror)
			)
		)
		(property "Device Type" "TPAD28"
			(at 0.0127 -3.1877 0)
			(unlocked yes)
			(layer "B.Fab")
			(hide yes)
			(effects
				(font
					(size 1.016 1.016)
					(thickness 0.1524)
				)
				(justify mirror)
			)
		)
		(duplicate_pad_numbers_are_jumpers no)
		(fp_poly
			(pts
				(arc
					(start 0.3556 0)
					(mid -0.3556 0)
					(end 0.3556 0)
				)
			)
			(stroke
				(width 0)
				(type default)
			)
			(fill no)
			(layer "B.CrtYd")
		)
		(fp_poly
			(pts
				(arc
					(start 0.6096 0)
					(mid -0.6096 0)
					(end 0.6096 0)
				)
			)
			(stroke
				(width 0)
				(type default)
			)
			(fill no)
			(layer "B.Fab")
		)
		(pad "1" smd circle
			(at 0 0 180)
			(size 0.7112 0.7112)
			(layers "B.Cu" "B.Mask" "B.Paste")
			(net "TP_GPIOT6")
		)
	)
	(footprint ""
		(layer "B.Cu")
		(at 231.394 -20.447)
		(property "Reference" "R821"
			(at 0 0 0)
			(layer "B.SilkS")
			(hide yes)
			(effects
				(font
					(size 1.27 1.27)
				)
				(justify mirror)
			)
		)
		(property "Value" "4K7R2F-GP"
			(at -0.064008 -3.993896 0)
			(unlocked yes)
			(layer "B.Fab")
			(hide yes)
			(effects
				(font
					(size 1.016 1.016)
					(thickness 0.1524)
				)
				(justify mirror)
			)
		)
		(property "Device Type" "R402H16"
			(at -0.064008 -5.517896 0)
			(unlocked yes)
			(layer "B.Fab")
			(hide yes)
			(effects
				(font
					(size 1.016 1.016)
					(thickness 0.1524)
				)
				(justify mirror)
			)
		)
		(duplicate_pad_numbers_are_jumpers no)
		(fp_line
			(start -0.508 -0.9398)
			(end 0.508 -0.9398)
			(stroke
				(width 0.1524)
				(type default)
			)
			(layer "B.SilkS")
		)
		(fp_line
			(start 0.508 -0.9398)
			(end 0.508 0.9398)
			(stroke
				(width 0.1524)
				(type default)
			)
			(layer "B.SilkS")
		)
		(fp_rect
			(start 0.508 0.9398)
			(end -0.508 -0.9398)
			(stroke
				(width 0)
				(type default)
			)
			(fill no)
			(layer "B.CrtYd")
		)
		(fp_rect
			(start 0.508 0.9398)
			(end -0.508 -0.9398)
			(stroke
				(width 0)
				(type default)
			)
			(fill no)
			(layer "B.Fab")
		)
		(pad "1" smd custom
			(at 0 -0.4445 180)
			(size 0.1397 0.1397)
			(layers "B.Cu" "B.Mask" "B.Paste")
			(net "BOOTSTRAP10")
			(options
				(clearance outline)
				(anchor circle)
			)
			(primitives
				(gr_poly
					(pts
						(arc
							(start -0.1778 0.2794)
							(mid -0.249642 0.249642)
							(end -0.2794 0.1778)
						)
						(arc
							(start -0.2794 -0.1778)
							(mid -0.249642 -0.249642)
							(end -0.1778 -0.2794)
						)
						(arc
							(start 0.1778 -0.2794)
							(mid 0.249642 -0.249642)
							(end 0.2794 -0.1778)
						)
						(arc
							(start 0.2794 0.1778)
							(mid 0.249642 0.249642)
							(end 0.1778 0.2794)
						)
					)
					(width 0)
					(fill yes)
				)
			)
		)
		(pad "2" smd custom
			(at 0 0.4445 180)
			(size 0.1397 0.1397)
			(layers "B.Cu" "B.Mask" "B.Paste")
			(net "DUT_VDDO")
			(options
				(clearance outline)
				(anchor circle)
			)
			(primitives
				(gr_poly
					(pts
						(arc
							(start -0.1778 0.2794)
							(mid -0.249642 0.249642)
							(end -0.2794 0.1778)
						)
						(arc
							(start -0.2794 -0.1778)
							(mid -0.249642 -0.249642)
							(end -0.1778 -0.2794)
						)
						(arc
							(start 0.1778 -0.2794)
							(mid 0.249642 -0.249642)
							(end 0.2794 -0.1778)
						)
						(arc
							(start 0.2794 0.1778)
							(mid 0.249642 0.249642)
							(end 0.1778 0.2794)
						)
					)
					(width 0)
					(fill yes)
				)
			)
		)
	)
	(footprint ""
		(layer "B.Cu")
		(at 215.4174 -21.8186 180)
		(property "Reference" "R29"
			(at 0 0 0)
			(layer "B.SilkS")
			(hide yes)
			(effects
				(font
					(size 1.27 1.27)
				)
				(justify mirror)
			)
		)
		(property "Value" "100KR2F-L1-GP"
			(at -0.064008 -3.993896 180)
			(unlocked yes)
			(layer "B.Fab")
			(hide yes)
			(effects
				(font
					(size 1.016 1.016)
					(thickness 0.1524)
				)
				(justify mirror)
			)
		)
		(property "Device Type" "R402H16"
			(at -0.064008 -5.517896 180)
			(unlocked yes)
			(layer "B.Fab")
			(hide yes)
			(effects
				(font
					(size 1.016 1.016)
					(thickness 0.1524)
				)
				(justify mirror)
			)
		)
		(duplicate_pad_numbers_are_jumpers no)
		(fp_line
			(start 0.508 -0.9398)
			(end 0.508 0.9398)
			(stroke
				(width 0.1524)
				(type default)
			)
			(layer "B.SilkS")
		)
		(fp_line
			(start -0.508 -0.9398)
			(end 0.508 -0.9398)
			(stroke
				(width 0.1524)
				(type default)
			)
			(layer "B.SilkS")
		)
		(fp_rect
			(start 0.508 0.9398)
			(end -0.508 -0.9398)
			(stroke
				(width 0)
				(type default)
			)
			(fill no)
			(layer "B.CrtYd")
		)
		(fp_rect
			(start 0.508 0.9398)
			(end -0.508 -0.9398)
			(stroke
				(width 0)
				(type default)
			)
			(fill no)
			(layer "B.Fab")
		)
		(pad "1" smd custom
			(at 0 -0.4445)
			(size 0.1397 0.1397)
			(layers "B.Cu" "B.Mask" "B.Paste")
			(net "GND")
			(options
				(clearance outline)
				(anchor circle)
			)
			(primitives
				(gr_poly
					(pts
						(arc
							(start -0.1778 0.2794)
							(mid -0.249642 0.249642)
							(end -0.2794 0.1778)
						)
						(arc
							(start -0.2794 -0.1778)
							(mid -0.249642 -0.249642)
							(end -0.1778 -0.2794)
						)
						(arc
							(start 0.1778 -0.2794)
							(mid 0.249642 -0.249642)
							(end 0.2794 -0.1778)
						)
						(arc
							(start 0.2794 0.1778)
							(mid 0.249642 0.249642)
							(end 0.1778 0.2794)
						)
					)
					(width 0)
					(fill yes)
				)
			)
		)
		(pad "2" smd custom
			(at 0 0.4445)
			(size 0.1397 0.1397)
			(layers "B.Cu" "B.Mask" "B.Paste")
			(net "PM8536_RST#")
			(options
				(clearance outline)
				(anchor circle)
			)
			(primitives
				(gr_poly
					(pts
						(arc
							(start -0.1778 0.2794)
							(mid -0.249642 0.249642)
							(end -0.2794 0.1778)
						)
						(arc
							(start -0.2794 -0.1778)
							(mid -0.249642 -0.249642)
							(end -0.1778 -0.2794)
						)
						(arc
							(start 0.1778 -0.2794)
							(mid 0.249642 -0.249642)
							(end 0.2794 -0.1778)
						)
						(arc
							(start 0.2794 0.1778)
							(mid 0.249642 0.249642)
							(end 0.1778 0.2794)
						)
					)
					(width 0)
					(fill yes)
				)
			)
		)
	)
	(footprint ""
		(layer "B.Cu")
		(at 152.532588 -33.541462 180)
		(property "Reference" "C226"
			(at 0 0 0)
			(layer "B.SilkS")
			(hide yes)
			(effects
				(font
					(size 1.27 1.27)
				)
				(justify mirror)
			)
		)
		(property "Value" "SCD1U10V2KX-5GP"
			(at -1.1811 -2.7051 180)
			(unlocked yes)
			(layer "B.Fab")
			(hide yes)
			(effects
				(font
					(size 1.016 1.016)
					(thickness 0.1524)
				)
				(justify mirror)
			)
		)
		(property "Device Type" "C402H22"
			(at -1.1811 -4.2291 180)
			(unlocked yes)
			(layer "B.Fab")
			(hide yes)
			(effects
				(font
					(size 1.016 1.016)
					(thickness 0.1524)
				)
				(justify mirror)
			)
		)
		(duplicate_pad_numbers_are_jumpers no)
		(fp_rect
			(start 0.4318 0.9525)
			(end -0.4318 -0.9525)
			(stroke
				(width 0)
				(type default)
			)
			(fill no)
			(layer "B.CrtYd")
		)
		(fp_rect
			(start 0.4318 0.9525)
			(end -0.4318 -0.9525)
			(stroke
				(width 0)
				(type default)
			)
			(fill no)
			(layer "B.Fab")
		)
		(pad "1" smd custom
			(at 0 -0.4445)
			(size 0.1524 0.1524)
			(layers "B.Cu" "B.Mask" "B.Paste")
			(net "GND")
			(options
				(clearance outline)
				(anchor circle)
			)
			(primitives
				(gr_poly
					(pts
						(arc
							(start 0.3048 0.2032)
							(mid 0.275042 0.275042)
							(end 0.2032 0.3048)
						)
						(arc
							(start -0.2032 0.3048)
							(mid -0.275042 0.275042)
							(end -0.3048 0.2032)
						)
						(arc
							(start -0.3048 -0.2032)
							(mid -0.275042 -0.275042)
							(end -0.2032 -0.3048)
						)
						(arc
							(start 0.2032 -0.3048)
							(mid 0.275042 -0.275042)
							(end 0.3048 -0.2032)
						)
					)
					(width 0)
					(fill yes)
				)
			)
		)
		(pad "2" smd custom
			(at 0 0.4445)
			(size 0.1524 0.1524)
			(layers "B.Cu" "B.Mask" "B.Paste")
			(net "P3V3_STBY")
			(options
				(clearance outline)
				(anchor circle)
			)
			(primitives
				(gr_poly
					(pts
						(arc
							(start 0.3048 0.2032)
							(mid 0.275042 0.275042)
							(end 0.2032 0.3048)
						)
						(arc
							(start -0.2032 0.3048)
							(mid -0.275042 0.275042)
							(end -0.3048 0.2032)
						)
						(arc
							(start -0.3048 -0.2032)
							(mid -0.275042 -0.275042)
							(end -0.2032 -0.3048)
						)
						(arc
							(start 0.2032 -0.3048)
							(mid 0.275042 -0.275042)
							(end 0.3048 -0.2032)
						)
					)
					(width 0)
					(fill yes)
				)
			)
		)
	)
	(footprint ""
		(layer "B.Cu")
		(at 73.787 -183.261)
		(property "Reference" "R9029"
			(at 0 0 0)
			(layer "B.SilkS")
			(hide yes)
			(effects
				(font
					(size 1.27 1.27)
				)
				(justify mirror)
			)
		)
		(property "Value" "4K7R2F-GP"
			(at -0.064008 -3.993896 0)
			(unlocked yes)
			(layer "B.Fab")
			(hide yes)
			(effects
				(font
					(size 1.016 1.016)
					(thickness 0.1524)
				)
				(justify mirror)
			)
		)
		(property "Device Type" "R402H16"
			(at -0.064008 -5.517896 0)
			(unlocked yes)
			(layer "B.Fab")
			(hide yes)
			(effects
				(font
					(size 1.016 1.016)
					(thickness 0.1524)
				)
				(justify mirror)
			)
		)
		(duplicate_pad_numbers_are_jumpers no)
		(fp_line
			(start -0.508 -0.9398)
			(end 0.508 -0.9398)
			(stroke
				(width 0.1524)
				(type default)
			)
			(layer "B.SilkS")
		)
		(fp_line
			(start 0.508 -0.9398)
			(end 0.508 0.9398)
			(stroke
				(width 0.1524)
				(type default)
			)
			(layer "B.SilkS")
		)
		(fp_rect
			(start 0.508 0.9398)
			(end -0.508 -0.9398)
			(stroke
				(width 0)
				(type default)
			)
			(fill no)
			(layer "B.CrtYd")
		)
		(fp_rect
			(start 0.508 0.9398)
			(end -0.508 -0.9398)
			(stroke
				(width 0)
				(type default)
			)
			(fill no)
			(layer "B.Fab")
		)
		(pad "1" smd custom
			(at 0 -0.4445 180)
			(size 0.1397 0.1397)
			(layers "B.Cu" "B.Mask" "B.Paste")
			(net "SSD_PERST#0")
			(options
				(clearance outline)
				(anchor circle)
			)
			(primitives
				(gr_poly
					(pts
						(arc
							(start -0.1778 0.2794)
							(mid -0.249642 0.249642)
							(end -0.2794 0.1778)
						)
						(arc
							(start -0.2794 -0.1778)
							(mid -0.249642 -0.249642)
							(end -0.1778 -0.2794)
						)
						(arc
							(start 0.1778 -0.2794)
							(mid 0.249642 -0.249642)
							(end 0.2794 -0.1778)
						)
						(arc
							(start 0.2794 0.1778)
							(mid 0.249642 0.249642)
							(end 0.1778 0.2794)
						)
					)
					(width 0)
					(fill yes)
				)
			)
		)
		(pad "2" smd custom
			(at 0 0.4445 180)
			(size 0.1397 0.1397)
			(layers "B.Cu" "B.Mask" "B.Paste")
			(net "GND")
			(options
				(clearance outline)
				(anchor circle)
			)
			(primitives
				(gr_poly
					(pts
						(arc
							(start -0.1778 0.2794)
							(mid -0.249642 0.249642)
							(end -0.2794 0.1778)
						)
						(arc
							(start -0.2794 -0.1778)
							(mid -0.249642 -0.249642)
							(end -0.1778 -0.2794)
						)
						(arc
							(start 0.1778 -0.2794)
							(mid 0.249642 -0.249642)
							(end 0.2794 -0.1778)
						)
						(arc
							(start 0.2794 0.1778)
							(mid 0.249642 0.249642)
							(end 0.1778 0.2794)
						)
					)
					(width 0)
					(fill yes)
				)
			)
		)
	)
	(footprint ""
		(layer "B.Cu")
		(at 32.738568 -119.55272 90)
		(property "Reference" "R564"
			(at 0 0 90)
			(layer "B.SilkS")
			(hide yes)
			(effects
				(font
					(size 1.27 1.27)
				)
				(justify mirror)
			)
		)
		(property "Value" "0R2J-2-GP"
			(at -0.064008 -3.993896 90)
			(unlocked yes)
			(layer "B.Fab")
			(hide yes)
			(effects
				(font
					(size 1.016 1.016)
					(thickness 0.1524)
				)
				(justify mirror)
			)
		)
		(property "Device Type" "R402H16"
			(at -0.064008 -5.517896 90)
			(unlocked yes)
			(layer "B.Fab")
			(hide yes)
			(effects
				(font
					(size 1.016 1.016)
					(thickness 0.1524)
				)
				(justify mirror)
			)
		)
		(duplicate_pad_numbers_are_jumpers no)
		(fp_line
			(start 0.508 -0.9398)
			(end 0.508 0.9398)
			(stroke
				(width 0.1524)
				(type default)
			)
			(layer "B.SilkS")
		)
		(fp_line
			(start -0.508 -0.9398)
			(end 0.508 -0.9398)
			(stroke
				(width 0.1524)
				(type default)
			)
			(layer "B.SilkS")
		)
		(fp_rect
			(start 0.508 0.9398)
			(end -0.508 -0.9398)
			(stroke
				(width 0)
				(type default)
			)
			(fill no)
			(layer "B.CrtYd")
		)
		(fp_rect
			(start 0.508 0.9398)
			(end -0.508 -0.9398)
			(stroke
				(width 0)
				(type default)
			)
			(fill no)
			(layer "B.Fab")
		)
		(pad "1" smd custom
			(at 0 -0.4445 270)
			(size 0.1397 0.1397)
			(layers "B.Cu" "B.Mask" "B.Paste")
			(net "FLA1_WPN")
			(options
				(clearance outline)
				(anchor circle)
			)
			(primitives
				(gr_poly
					(pts
						(arc
							(start -0.1778 0.2794)
							(mid -0.249642 0.249642)
							(end -0.2794 0.1778)
						)
						(arc
							(start -0.2794 -0.1778)
							(mid -0.249642 -0.249642)
							(end -0.1778 -0.2794)
						)
						(arc
							(start 0.1778 -0.2794)
							(mid 0.249642 -0.249642)
							(end 0.2794 -0.1778)
						)
						(arc
							(start 0.2794 0.1778)
							(mid 0.249642 0.249642)
							(end 0.1778 0.2794)
						)
					)
					(width 0)
					(fill yes)
				)
			)
		)
		(pad "2" smd custom
			(at 0 0.4445 270)
			(size 0.1397 0.1397)
			(layers "B.Cu" "B.Mask" "B.Paste")
			(net "FLA1_WPN_R")
			(options
				(clearance outline)
				(anchor circle)
			)
			(primitives
				(gr_poly
					(pts
						(arc
							(start -0.1778 0.2794)
							(mid -0.249642 0.249642)
							(end -0.2794 0.1778)
						)
						(arc
							(start -0.2794 -0.1778)
							(mid -0.249642 -0.249642)
							(end -0.1778 -0.2794)
						)
						(arc
							(start 0.1778 -0.2794)
							(mid 0.249642 -0.249642)
							(end 0.2794 -0.1778)
						)
						(arc
							(start 0.2794 0.1778)
							(mid 0.249642 0.249642)
							(end 0.1778 0.2794)
						)
					)
					(width 0)
					(fill yes)
				)
			)
		)
	)
)
